# T6G (Grand Teton) — schematic netlist excerpt (pin names and nets, part order shuffled) for the footprints in the layout excerpt that follows; sources: Cadence DE-HDL packaged netlist, KiCad conversion of 04192023_DAF0TMB3IC0_F0TG_MB_C_brd_V02_OCP.brd

J1  SCONN288_DDR506112002KQ  IO  pkg DDR288S_1-1VXC  page 86
  VIN_BULK0  = P12V_MEM_CPU0
  RFU0  = NC
  VIN_MGMT  = P3V3_AUX
  HSCL  = I3C_SPD_DDRA_CPU0_SCL
  HSDA  = I3C_SPD_DDRA_CPU0_SDA
  VSS0  = GND
  DQ0_A  = M_A_CPU0_SA_DQ<0>
  VSS1  = GND
  DQ1_A  = M_A_CPU0_SA_DQ<1>
  VSS2  = GND
  DQS0_A_T  = M_A_CPU0_SA_DQS_DP<0>
  DQS0_A_C  = M_A_CPU0_SA_DQS_DN<0>
  VSS3  = GND
  DQ4_A  = M_A_CPU0_SA_DQ<4>
  VSS4  = GND
  DQ5_A  = M_A_CPU0_SA_DQ<5>
  VSS5  = GND
  DQ8_A  = M_A_CPU0_SA_DQ<8>
  VSS6  = GND
  DQ9_A  = M_A_CPU0_SA_DQ<9>
  VSS7  = GND
  DQS1_A_T  = M_A_CPU0_SA_DQS_DP<1>
  DQS1_A_C  = M_A_CPU0_SA_DQS_DN<1>
  VSS8  = GND
  DQ12_A  = M_A_CPU0_SA_DQ<12>
  VSS9  = GND
  DQ13_A  = M_A_CPU0_SA_DQ<13>
  VSS10  = GND
  DQ16_A  = M_A_CPU0_SA_DQ<16>
  VSS11  = GND
  DQ17_A  = M_A_CPU0_SA_DQ<17>
  VSS12  = GND
  DQS2_A_T  = M_A_CPU0_SA_DQS_DP<2>
  DQS2_A_C  = M_A_CPU0_SA_DQS_DN<2>
  VSS13  = GND
  DQ20_A  = M_A_CPU0_SA_DQ<20>
  VSS14  = GND
  DQ21_A  = M_A_CPU0_SA_DQ<21>
  VSS15  = GND
  DQ24_A  = M_A_CPU0_SA_DQ<24>
  VSS16  = GND
  DQ25_A  = M_A_CPU0_SA_DQ<25>
  VSS17  = GND
  DQS3_A_T  = M_A_CPU0_SA_DQS_DP<3>
  DQS3_A_C  = M_A_CPU0_SA_DQS_DN<3>
  VSS18  = GND
  DQ28_A  = M_A_CPU0_SA_DQ<28>
  VSS19  = GND
  DQ29_A  = M_A_CPU0_SA_DQ<29>
  VSS20  = GND
  CB0_A  = M_A_CPU0_SA_CB<0>
  VSS21  = GND
  CB1_A  = M_A_CPU0_SA_CB<1>
  VSS22  = GND
  DQS4_A_T  = M_A_CPU0_SA_DQS_DP<4>
  DQS4_A_C  = M_A_CPU0_SA_DQS_DN<4>
  VSS23  = GND
  CB4_A  = M_A_CPU0_SA_CB<4>
  VSS24  = GND
  CB5_A  = M_A_CPU0_SA_CB<5>
  VSS25  = GND
  ALERT_N  = M_A_CPU0_ALERT_N
  VSS26  = GND
  CS0_A_N  = M_A_CPU0_SA_CS_N<0>
  VSS27  = GND
  CA0_A  = M_A_CPU0_SA_CA<0>
  VSS28  = GND
  CA2_A  = M_A_CPU0_SA_CA<2>
  VSS29  = GND
  CA4_A  = M_A_CPU0_SA_CA<4>
  VSS30  = GND
  CA6_A  = M_A_CPU0_SA_CA<6>
  VSS31  = GND
  PAR_A  = M_A_CPU0_SA_PAR
  VSS32  = GND
  CA0_B  = M_A_CPU0_SB_CA<0>
  VSS33  = GND
  CA2_B  = M_A_CPU0_SB_CA<2>
  VSS34  = GND
  CA4_B  = M_A_CPU0_SB_CA<4>
  VSS35  = GND
  CA6_B  = M_A_CPU0_SB_CA<6>
  VSS36  = GND
  CS0_B_N  = M_A_CPU0_SB_CS_N<0>
  VSS37  = GND
  \lbd||rsp_a_n\  = M_A_CPU0_SA_RSP<0>
  \lbs||rsp_b_n\  = M_A_CPU0_SB_RSP<0>
  VSS38  = GND
  CB4_B  = M_A_CPU0_SB_CB<4>
  VSS39  = GND
  CB5_B  = M_A_CPU0_SB_CB<5>
  VSS40  = GND
  \dqs9_b_t||tdqs9_b_t||dbi4_b_n\  = M_A_CPU0_SB_DQS_DP<9>
  \dqs9_b_c||tdqs9_b_c\  = M_A_CPU0_SB_DQS_DN<9>
  VSS41  = GND
  CB0_B  = M_A_CPU0_SB_CB<0>
  VSS42  = GND
  CB1_B  = M_A_CPU0_SB_CB<1>
  VSS43  = GND
  DQ0_B  = M_A_CPU0_SB_DQ<0>
  VSS44  = GND
  DQ1_B  = M_A_CPU0_SB_DQ<1>
  VSS45  = GND
  DQS0_B_T  = M_A_CPU0_SB_DQS_DP<0>
  DQS0_B_C  = M_A_CPU0_SB_DQS_DN<0>
  VSS46  = GND
  DQ4_B  = M_A_CPU0_SB_DQ<4>
  VSS47  = GND
  DQ5_B  = M_A_CPU0_SB_DQ<5>
  VSS48  = GND
  DQ8_B  = M_A_CPU0_SB_DQ<8>
  VSS49  = GND
  DQ9_B  = M_A_CPU0_SB_DQ<9>
  VSS50  = GND
  DQS1_B_T  = M_A_CPU0_SB_DQS_DP<1>
  DQS1_B_C  = M_A_CPU0_SB_DQS_DN<1>
  VSS51  = GND
  DQ12_B  = M_A_CPU0_SB_DQ<12>
  VSS52  = GND
  DQ13_B  = M_A_CPU0_SB_DQ<13>
  VSS53  = GND
  DQ16_B  = M_A_CPU0_SB_DQ<16>
  VSS54  = GND
  DQ17_B  = M_A_CPU0_SB_DQ<17>
  VSS55  = GND
  DQS2_B_T  = M_A_CPU0_SB_DQS_DP<2>
  DQS2_B_C  = M_A_CPU0_SB_DQS_DN<2>
  VSS56  = GND
  DQ20_B  = M_A_CPU0_SB_DQ<20>
  VSS57  = GND
  DQ21_B  = M_A_CPU0_SB_DQ<21>
  VSS58  = GND
  DQ24_B  = M_A_CPU0_SB_DQ<24>
  VSS59  = GND
  DQ25_B  = M_A_CPU0_SB_DQ<25>
  VSS60  = GND
  DQS3_B_T  = M_A_CPU0_SB_DQS_DP<3>
  DQS3_B_C  = M_A_CPU0_SB_DQS_DN<3>
  VSS61  = GND
  DQ28_B  = M_A_CPU0_SB_DQ<28>
  VSS62  = GND
  DQ29_B  = M_A_CPU0_SB_DQ<29>
  VSS63  = GND
  RFU1  = NC
  VIN_BULK1  = P12V_MEM_CPU0
  VIN_BULK2  = P12V_MEM_CPU0
  \pwr_good||fail_n\  = PWRGD_CHA_CPU0_DIMM0
  HAS  = PD_CHA_CPU0_DIMM0_SAA
  RFU2  = NC
  RFU3  = NC
  VSS64  = GND
  DQ2_A  = M_A_CPU0_SA_DQ<2>
  VSS65  = GND
  DQ3_A  = M_A_CPU0_SA_DQ<3>
  VSS66  = GND
  \dqs5_a_c||tdqs5_a_c||dqs5_a_t||tdqs5_a_t\  = M_A_CPU0_SA_DQS_DN<5>
  \dqs5_a_t||tdqs5_a_t\  = M_A_CPU0_SA_DQS_DP<5>
  VSS67  = GND
  DQ6_A  = M_A_CPU0_SA_DQ<6>
  VSS68  = GND
  DQ7_A  = M_A_CPU0_SA_DQ<7>
  VSS69  = GND
  DQ10_A  = M_A_CPU0_SA_DQ<10>
  VSS70  = GND
  DQ11_A  = M_A_CPU0_SA_DQ<11>
  VSS71  = GND
  \dqs6_a_c||tdqs6_a_c||dqs6_a_t||tdqs6_a_t\  = M_A_CPU0_SA_DQS_DN<6>
  \dqs6_a_t||tdqs6_a_t\  = M_A_CPU0_SA_DQS_DP<6>
  VSS72  = GND
  DQ14_A  = M_A_CPU0_SA_DQ<14>
  VSS73  = GND
  DQ15_A  = M_A_CPU0_SA_DQ<15>
  VSS74  = GND
  DQ18_A  = M_A_CPU0_SA_DQ<18>
  VSS75  = GND
  DQ19_A  = M_A_CPU0_SA_DQ<19>
  VSS76  = GND
  \dqs7_a_c||tdqs7_a_c\  = M_A_CPU0_SA_DQS_DN<7>
  \dqs7_a_t||tdqs7_a_t\  = M_A_CPU0_SA_DQS_DP<7>
  VSS77  = GND
  DQ22_A  = M_A_CPU0_SA_DQ<22>
  VSS78  = GND
  DQ23_A  = M_A_CPU0_SA_DQ<23>
  VSS79  = GND
  DQ26_A  = M_A_CPU0_SA_DQ<26>
  VSS80  = GND
  DQ27_A  = M_A_CPU0_SA_DQ<27>
  VSS81  = GND
  \dqs8_a_c||tdqs8_a_c\  = M_A_CPU0_SA_DQS_DN<8>
  \dqs8_a_t||tdqs8_a_t\  = M_A_CPU0_SA_DQS_DP<8>
  VSS82  = GND
  DQ30_A  = M_A_CPU0_SA_DQ<30>
  VSS83  = GND
  DQ31_A  = M_A_CPU0_SA_DQ<31>
  VSS84  = GND
  CB2_A  = M_A_CPU0_SA_CB<2>
  VSS85  = GND
  CB3_A  = M_A_CPU0_SA_CB<3>
  VSS86  = GND
  \dqs9_a_c||tdqs9_a_c\  = M_A_CPU0_SA_DQS_DN<9>
  \dqs9_a_t||tdqs9_a_t\  = M_A_CPU0_SA_DQS_DP<9>
  VSS87  = GND
  CB6_A  = M_A_CPU0_SA_CB<6>
  VSS88  = GND
  CB7_A  = M_A_CPU0_SA_CB<7>
  VSS89  = GND
  RESET_N  = M_A_CPU0_RESET_N
  VSS90  = GND
  CS1_A_N  = M_A_CPU0_SA_CS_N<1>
  VSS91  = GND
  CA1_A  = M_A_CPU0_SA_CA<1>
  VSS92  = GND
  CA3_A  = M_A_CPU0_SA_CA<3>
  VSS93  = GND
  CA5_A  = M_A_CPU0_SA_CA<5>
  VSS94  = GND
  CK_T  = M_A_CPU0_CLK_DP<0>
  CK_C  = M_A_CPU0_CLK_DN<0>
  VSS95  = GND
  RFU4  = NC
  CA1_B  = M_A_CPU0_SB_CA<1>
  VSS96  = GND
  CA3_B  = M_A_CPU0_SB_CA<3>
  VSS97  = GND
  CA5_B  = M_A_CPU0_SB_CA<5>
  VSS98  = GND
  PAR_B  = M_A_CPU0_SB_PAR
  VSS99  = GND
  CS1_B_N  = M_A_CPU0_SB_CS_N<1>
  VSS100  = GND
  RFU5  = NC
  RFU6  = NC
  VSS101  = GND
  CB6_B  = M_A_CPU0_SB_CB<6>
  VSS102  = GND
  CB7_B  = M_A_CPU0_SB_CB<7>
  VSS103  = GND
  DQS4_B_C  = M_A_CPU0_SB_DQS_DN<4>
  DQS4_B_T  = M_A_CPU0_SB_DQS_DP<4>
  VSS104  = GND
  CB2_B  = M_A_CPU0_SB_CB<2>
  VSS105  = GND
  CB3_B  = M_A_CPU0_SB_CB<3>
  VSS106  = GND
  DQ2_B  = M_A_CPU0_SB_DQ<2>
  VSS107  = GND
  DQ3_B  = M_A_CPU0_SB_DQ<3>
  VSS108  = GND
  \dqs5_b_c||tdqs5_b_c\  = M_A_CPU0_SB_DQS_DN<5>
  \dqs5_b_t||tdqs5_b_t\  = M_A_CPU0_SB_DQS_DP<5>
  VSS109  = GND
  DQ6_B  = M_A_CPU0_SB_DQ<6>
  VSS110  = GND
  DQ7_B  = M_A_CPU0_SB_DQ<7>
  VSS111  = GND
  DQ10_B  = M_A_CPU0_SB_DQ<10>
  VSS112  = GND
  DQ11_B  = M_A_CPU0_SB_DQ<11>
  VSS113  = GND
  \dqs6_b_c||tdqs6_b_c\  = M_A_CPU0_SB_DQS_DN<6>
  \dqs6_b_t||tdqs6_b_t\  = M_A_CPU0_SB_DQS_DP<6>
  VSS114  = GND
  DQ14_B  = M_A_CPU0_SB_DQ<14>
  VSS115  = GND
  DQ15_B  = M_A_CPU0_SB_DQ<15>
  VSS116  = GND
  DQ18_B  = M_A_CPU0_SB_DQ<18>
  VSS117  = GND
  DQ19_B  = M_A_CPU0_SB_DQ<19>
  VSS118  = GND
  \dqs7_b_c||tdqs7_b_c\  = M_A_CPU0_SB_DQS_DN<7>
  \dqs7_b_t||tdqs7_b_t\  = M_A_CPU0_SB_DQS_DP<7>
  VSS119  = GND
  DQ22_B  = M_A_CPU0_SB_DQ<22>
  VSS120  = GND
  DQ23_B  = M_A_CPU0_SB_DQ<23>
  VSS121  = GND
  DQ26_B  = M_A_CPU0_SB_DQ<26>
  VSS122  = GND
  DQ27_B  = M_A_CPU0_SB_DQ<27>
  VSS123  = GND
  \dqs8_b_c||tdqs8_b_c\  = M_A_CPU0_SB_DQS_DN<8>
  \dqs8_b_t||tdqs8_b_t\  = M_A_CPU0_SB_DQS_DP<8>
  VSS124  = GND
  DQ30_B  = M_A_CPU0_SB_DQ<30>
  VSS125  = GND
  DQ31_B  = M_A_CPU0_SB_DQ<31>
  VSS126  = GND
  G1  = GND
  G2  = GND
  G3  = GND

(kicad_pcb
	(version 20260206)
	(generator "pcbnew")
	(generator_version "10.0")
	(general
		(thickness 1.6)
		(legacy_teardrops no)
	)
	(paper "A4")
	(title_block
		(title "04192023_DAF0TMB3IC0_F0TG_MB_C_brd_V02_OCP.brd")
		(comment 1 "Grand Teton / footprint 2352 of 8354 (J1), pads 139-184 of 291")
	)
	(layers
		(0 "F.Cu" signal "TOP")
		(4 "In1.Cu" signal "GND")
		(6 "In2.Cu" signal "IN1")
		(8 "In3.Cu" signal "GND1")
		(10 "In4.Cu" signal "IN2")
		(12 "In5.Cu" signal "GND2")
		(14 "In6.Cu" signal "IN3")
		(16 "In7.Cu" signal "GND3")
		(18 "In8.Cu" signal "VCC")
		(20 "In9.Cu" signal "VCC1")
		(22 "In10.Cu" signal "GND4")
		(24 "In11.Cu" signal "IN4")
		(26 "In12.Cu" signal "GND5")
		(28 "In13.Cu" signal "IN5")
		(30 "In14.Cu" signal "GND6")
		(32 "In15.Cu" signal "IN6")
		(34 "In16.Cu" signal "GND7")
		(2 "B.Cu" signal "BOTTOM")
		(9 "F.Adhes" user "F.Adhesive")
		(11 "B.Adhes" user "B.Adhesive")
		(13 "F.Paste" user "Package Geometry/Pastemask Top")
		(15 "B.Paste" user "Package Geometry/Pastemask Bottom")
		(5 "F.SilkS" user "Ref Des/Silkscreen Top")
		(7 "B.SilkS" user "Ref Des/Silkscreen Bottom")
		(1 "F.Mask" user "Board Geometry/Soldermask Top")
		(3 "B.Mask" user "Board Geometry/Soldermask Bottom")
		(17 "Dwgs.User" user "User.Drawings")
		(19 "Cmts.User" user "User.Comments")
		(21 "Eco1.User" user "User.Eco1")
		(23 "Eco2.User" user "User.Eco2")
		(25 "Edge.Cuts" user "Board Geometry/Outline")
		(27 "Margin" user)
		(31 "F.CrtYd" user "Package Geometry/Place Bound Top")
		(29 "B.CrtYd" user "Package Geometry/Place Bound Bottom")
		(35 "F.Fab" user "Ref Des/Assembly Top")
		(33 "B.Fab" user "Ref Des/Assembly Bottom")
	)
	(footprint ""
		(layer "F.Cu")
		(at 305.31816 -255.560068 180)
		(property "Reference" "J1"
			(at -2.2098 -81.984088 0)
			(unlocked yes)
			(layer "F.SilkS")
			(effects
				(font
					(size 0.7874 0.5842)
					(thickness 0.1524)
				)
			)
		)
		(property "Value" ""
			(at 0 0 180)
			(layer "F.Fab")
			(effects
				(font
					(size 1.27 1.27)
				)
			)
		)
		(duplicate_pad_numbers_are_jumpers no)
		(pad "139" smd rect
			(at -2.050034 59.075066 90)
			(size 0.519938 1.4986)
			(layers "F.Cu" "F.Mask" "F.Paste")
			(net "GND")
		)
		(pad "140" smd rect
			(at -2.050034 59.92495 90)
			(size 0.519938 1.4986)
			(layers "F.Cu" "F.Mask" "F.Paste")
			(net "M_A_CPU0_SB_DQ<28>")
		)
		(pad "141" smd rect
			(at -2.050034 60.775088 90)
			(size 0.519938 1.4986)
			(layers "F.Cu" "F.Mask" "F.Paste")
			(net "GND")
		)
		(pad "142" smd rect
			(at -2.050034 61.624972 90)
			(size 0.519938 1.4986)
			(layers "F.Cu" "F.Mask" "F.Paste")
			(net "M_A_CPU0_SB_DQ<29>")
		)
		(pad "143" smd rect
			(at -2.050034 62.47511 90)
			(size 0.519938 1.4986)
			(layers "F.Cu" "F.Mask" "F.Paste")
			(net "GND")
		)
		(pad "144" smd rect
			(at -2.050034 63.324994 90)
			(size 0.519938 1.4986)
			(layers "F.Cu" "F.Mask" "F.Paste")
			(net "Net_2250")
		)
		(pad "145" smd rect
			(at 2.050034 -63.324994 90)
			(size 0.519938 1.4986)
			(layers "F.Cu" "F.Mask" "F.Paste")
			(net "P12V_MEM_CPU0")
		)
		(pad "146" smd rect
			(at 2.050034 -62.47511 90)
			(size 0.519938 1.4986)
			(layers "F.Cu" "F.Mask" "F.Paste")
			(net "P12V_MEM_CPU0")
		)
		(pad "147" smd rect
			(at 2.050034 -61.624972 90)
			(size 0.519938 1.4986)
			(layers "F.Cu" "F.Mask" "F.Paste")
			(net "PWRGD_CHA_CPU0_DIMM0")
		)
		(pad "148" smd rect
			(at 2.050034 -60.775088 90)
			(size 0.519938 1.4986)
			(layers "F.Cu" "F.Mask" "F.Paste")
			(net "PD_CHA_CPU0_DIMM0_SAA")
		)
		(pad "149" smd rect
			(at 2.050034 -59.92495 90)
			(size 0.519938 1.4986)
			(layers "F.Cu" "F.Mask" "F.Paste")
			(net "Net_2251")
		)
		(pad "150" smd rect
			(at 2.050034 -59.075066 90)
			(size 0.519938 1.4986)
			(layers "F.Cu" "F.Mask" "F.Paste")
			(net "Net_2252")
		)
		(pad "151" smd rect
			(at 2.050034 -58.224928 90)
			(size 0.519938 1.4986)
			(layers "F.Cu" "F.Mask" "F.Paste")
			(net "GND")
		)
		(pad "152" smd rect
			(at 2.050034 -57.375044 90)
			(size 0.519938 1.4986)
			(layers "F.Cu" "F.Mask" "F.Paste")
			(net "M_A_CPU0_SA_DQ<2>")
		)
		(pad "153" smd rect
			(at 2.050034 -56.524906 90)
			(size 0.519938 1.4986)
			(layers "F.Cu" "F.Mask" "F.Paste")
			(net "GND")
		)
		(pad "154" smd rect
			(at 2.050034 -55.675022 90)
			(size 0.519938 1.4986)
			(layers "F.Cu" "F.Mask" "F.Paste")
			(net "M_A_CPU0_SA_DQ<3>")
		)
		(pad "155" smd rect
			(at 2.050034 -54.824884 90)
			(size 0.519938 1.4986)
			(layers "F.Cu" "F.Mask" "F.Paste")
			(net "GND")
		)
		(pad "156" smd rect
			(at 2.050034 -53.975 90)
			(size 0.519938 1.4986)
			(layers "F.Cu" "F.Mask" "F.Paste")
			(net "M_A_CPU0_SA_DQS_DN<5>")
		)
		(pad "157" smd rect
			(at 2.050034 -53.125116 90)
			(size 0.519938 1.4986)
			(layers "F.Cu" "F.Mask" "F.Paste")
			(net "M_A_CPU0_SA_DQS_DP<5>")
		)
		(pad "158" smd rect
			(at 2.050034 -52.274978 90)
			(size 0.519938 1.4986)
			(layers "F.Cu" "F.Mask" "F.Paste")
			(net "GND")
		)
		(pad "159" smd rect
			(at 2.050034 -51.425094 90)
			(size 0.519938 1.4986)
			(layers "F.Cu" "F.Mask" "F.Paste")
			(net "M_A_CPU0_SA_DQ<6>")
		)
		(pad "160" smd rect
			(at 2.050034 -50.574956 90)
			(size 0.519938 1.4986)
			(layers "F.Cu" "F.Mask" "F.Paste")
			(net "GND")
		)
		(pad "161" smd rect
			(at 2.050034 -49.725072 90)
			(size 0.519938 1.4986)
			(layers "F.Cu" "F.Mask" "F.Paste")
			(net "M_A_CPU0_SA_DQ<7>")
		)
		(pad "162" smd rect
			(at 2.050034 -48.874934 90)
			(size 0.519938 1.4986)
			(layers "F.Cu" "F.Mask" "F.Paste")
			(net "GND")
		)
		(pad "163" smd rect
			(at 2.050034 -48.02505 90)
			(size 0.519938 1.4986)
			(layers "F.Cu" "F.Mask" "F.Paste")
			(net "M_A_CPU0_SA_DQ<10>")
		)
		(pad "164" smd rect
			(at 2.050034 -47.174912 90)
			(size 0.519938 1.4986)
			(layers "F.Cu" "F.Mask" "F.Paste")
			(net "GND")
		)
		(pad "165" smd rect
			(at 2.050034 -46.325028 90)
			(size 0.519938 1.4986)
			(layers "F.Cu" "F.Mask" "F.Paste")
			(net "M_A_CPU0_SA_DQ<11>")
		)
		(pad "166" smd rect
			(at 2.050034 -45.47489 90)
			(size 0.519938 1.4986)
			(layers "F.Cu" "F.Mask" "F.Paste")
			(net "GND")
		)
		(pad "167" smd rect
			(at 2.050034 -44.625006 90)
			(size 0.519938 1.4986)
			(layers "F.Cu" "F.Mask" "F.Paste")
			(net "M_A_CPU0_SA_DQS_DN<6>")
		)
		(pad "168" smd rect
			(at 2.050034 -43.775122 90)
			(size 0.519938 1.4986)
			(layers "F.Cu" "F.Mask" "F.Paste")
			(net "M_A_CPU0_SA_DQS_DP<6>")
		)
		(pad "169" smd rect
			(at 2.050034 -42.924984 90)
			(size 0.519938 1.4986)
			(layers "F.Cu" "F.Mask" "F.Paste")
			(net "GND")
		)
		(pad "170" smd rect
			(at 2.050034 -42.0751 90)
			(size 0.519938 1.4986)
			(layers "F.Cu" "F.Mask" "F.Paste")
			(net "M_A_CPU0_SA_DQ<14>")
		)
		(pad "171" smd rect
			(at 2.050034 -41.224962 90)
			(size 0.519938 1.4986)
			(layers "F.Cu" "F.Mask" "F.Paste")
			(net "GND")
		)
		(pad "172" smd rect
			(at 2.050034 -40.375078 90)
			(size 0.519938 1.4986)
			(layers "F.Cu" "F.Mask" "F.Paste")
			(net "M_A_CPU0_SA_DQ<15>")
		)
		(pad "173" smd rect
			(at 2.050034 -39.52494 90)
			(size 0.519938 1.4986)
			(layers "F.Cu" "F.Mask" "F.Paste")
			(net "GND")
		)
		(pad "174" smd rect
			(at 2.050034 -38.675056 90)
			(size 0.519938 1.4986)
			(layers "F.Cu" "F.Mask" "F.Paste")
			(net "M_A_CPU0_SA_DQ<18>")
		)
		(pad "175" smd rect
			(at 2.050034 -37.824918 90)
			(size 0.519938 1.4986)
			(layers "F.Cu" "F.Mask" "F.Paste")
			(net "GND")
		)
		(pad "176" smd rect
			(at 2.050034 -36.975034 90)
			(size 0.519938 1.4986)
			(layers "F.Cu" "F.Mask" "F.Paste")
			(net "M_A_CPU0_SA_DQ<19>")
		)
		(pad "177" smd rect
			(at 2.050034 -36.124896 90)
			(size 0.519938 1.4986)
			(layers "F.Cu" "F.Mask" "F.Paste")
			(net "GND")
		)
		(pad "178" smd rect
			(at 2.050034 -35.275012 90)
			(size 0.519938 1.4986)
			(layers "F.Cu" "F.Mask" "F.Paste")
			(net "M_A_CPU0_SA_DQS_DN<7>")
		)
		(pad "179" smd rect
			(at 2.050034 -34.425128 90)
			(size 0.519938 1.4986)
			(layers "F.Cu" "F.Mask" "F.Paste")
			(net "M_A_CPU0_SA_DQS_DP<7>")
		)
		(pad "180" smd rect
			(at 2.050034 -33.57499 90)
			(size 0.519938 1.4986)
			(layers "F.Cu" "F.Mask" "F.Paste")
			(net "GND")
		)
		(pad "181" smd rect
			(at 2.050034 -32.725106 90)
			(size 0.519938 1.4986)
			(layers "F.Cu" "F.Mask" "F.Paste")
			(net "M_A_CPU0_SA_DQ<22>")
		)
		(pad "182" smd rect
			(at 2.050034 -31.874968 90)
			(size 0.519938 1.4986)
			(layers "F.Cu" "F.Mask" "F.Paste")
			(net "GND")
		)
		(pad "183" smd rect
			(at 2.050034 -31.025084 90)
			(size 0.519938 1.4986)
			(layers "F.Cu" "F.Mask" "F.Paste")
			(net "M_A_CPU0_SA_DQ<23>")
		)
		(pad "184" smd rect
			(at 2.050034 -30.174946 90)
			(size 0.519938 1.4986)
			(layers "F.Cu" "F.Mask" "F.Paste")
			(net "GND")
		)
	)
)
